# BASEBOARD_FAB2 (Tioga Pass) — schematic netlist excerpt (pin names and nets, part order shuffled) for the footprints in the layout excerpt that follows; sources: Cadence DE-HDL packaged netlist, KiCad conversion of Wiwynn_Tioga_Pass_MB.brd

C5P1  CAP  100UF 4V 20% X5R  pkg 0805  page 220 : A = PVDDQ_DEF ; B = GND
C22W17  SC22U16V5MX-4-GP  20%  pkg SMD-BCG5  page 214 : \1\ = VR_FET_SW_P12V_STBY_PVCCIN_CPU0 ; \2\ = GND
C1M21  CAP_A  1.0UF 6.3V 10% X6S  pkg 0402V  page 186 : A = P3V3 ; B = GND

(kicad_pcb
	(version 20260206)
	(generator "pcbnew")
	(generator_version "10.0")
	(general
		(thickness 1.6)
		(legacy_teardrops no)
	)
	(paper "A4")
	(title_block
		(title "Wiwynn_Tioga_Pass_MB.brd")
		(comment 1 "Tioga Pass / footprints 2420-2422 of 4770")
	)
	(layers
		(0 "F.Cu" signal "TOP")
		(4 "In1.Cu" signal "L2GND")
		(6 "In2.Cu" signal "L3")
		(8 "In3.Cu" signal "L4GND")
		(10 "In4.Cu" signal "L5")
		(12 "In5.Cu" signal "L6GND")
		(14 "In6.Cu" signal "L7VCC")
		(16 "In7.Cu" signal "L8VCC")
		(18 "In8.Cu" signal "L9GND")
		(20 "In9.Cu" signal "L10")
		(22 "In10.Cu" signal "L11GND")
		(24 "In11.Cu" signal "L12")
		(26 "In12.Cu" signal "L13GND")
		(2 "B.Cu" signal "BOTTOM")
		(9 "F.Adhes" user "F.Adhesive")
		(11 "B.Adhes" user "B.Adhesive")
		(13 "F.Paste" user "Package Geometry/Pastemask Top")
		(15 "B.Paste" user "Package Geometry/Pastemask Bottom")
		(5 "F.SilkS" user "Ref Des/Silkscreen Top")
		(7 "B.SilkS" user "Ref Des/Silkscreen Bottom")
		(1 "F.Mask" user "Board Geometry/Soldermask Top")
		(3 "B.Mask" user "Board Geometry/Soldermask Bottom")
		(17 "Dwgs.User" user "User.Drawings")
		(19 "Cmts.User" user "User.Comments")
		(21 "Eco1.User" user "User.Eco1")
		(23 "Eco2.User" user "User.Eco2")
		(25 "Edge.Cuts" user "Board Geometry/Outline")
		(27 "Margin" user)
		(31 "F.CrtYd" user "Package Geometry/Place Bound Top")
		(29 "B.CrtYd" user "Package Geometry/Place Bound Bottom")
		(35 "F.Fab" user "Ref Des/Assembly Top")
		(33 "B.Fab" user "Ref Des/Assembly Bottom")
	)
	(footprint ""
		(layer "B.Cu")
		(at 189.992 -54.229 90)
		(property "Reference" "C22W17"
			(at 0 0 90)
			(layer "B.SilkS")
			(hide yes)
			(effects
				(font
					(size 1.27 1.27)
				)
				(justify mirror)
			)
		)
		(property "Value" "*"
			(at 0.0762 -6.2357 90)
			(unlocked yes)
			(layer "B.Fab")
			(hide yes)
			(effects
				(font
					(size 1.27 1.016)
					(thickness 0.1524)
				)
				(justify mirror)
			)
		)
		(property "Device Type" "SC22U16V5MX-4-GP_SMD-BCG5-SC22A"
			(at 0.0762 -8.2677 90)
			(unlocked yes)
			(layer "B.Fab")
			(hide yes)
			(effects
				(font
					(size 1.27 1.016)
					(thickness 0.1524)
				)
				(justify mirror)
			)
		)
		(duplicate_pad_numbers_are_jumpers no)
		(fp_line
			(start -0.635 0)
			(end 0.635 0)
			(stroke
				(width 0.508)
				(type default)
			)
			(layer "B.SilkS")
		)
		(fp_rect
			(start 0.9652 1.778)
			(end -0.9652 -1.778)
			(stroke
				(width 0)
				(type default)
			)
			(fill no)
			(layer "B.CrtYd")
		)
		(fp_poly
			(pts
				(xy 0.9652 -1.778) (xy -0.9652 -1.778) (xy -0.9652 1.778) (xy 0.9652 1.778)
			)
			(stroke
				(width 0)
				(type default)
			)
			(fill no)
			(layer "B.Fab")
		)
		(pad "1" smd rect
			(at 0 -0.9652 270)
			(size 1.397 1.143)
			(layers "B.Cu" "B.Mask" "B.Paste")
			(net "VR_FET_SW_P12V_STBY_PVCCIN_CPU0")
		)
		(pad "2" smd rect
			(at 0 0.9652 270)
			(size 1.397 1.143)
			(layers "B.Cu" "B.Mask" "B.Paste")
			(net "GND")
		)
	)
	(footprint ""
		(layer "B.Cu")
		(at 267.552424 -85.075014)
		(property "Reference" "C5P1"
			(at 0 0 0)
			(layer "B.SilkS")
			(hide yes)
			(effects
				(font
					(size 1.27 1.27)
				)
				(justify mirror)
			)
		)
		(property "Value" ""
			(at 0 0 0)
			(layer "B.Fab")
			(effects
				(font
					(size 1.27 1.27)
				)
				(justify mirror)
			)
		)
		(duplicate_pad_numbers_are_jumpers no)
		(fp_poly
			(pts
				(xy 0.7239 -0.2159) (xy -0.7239 -0.2159) (xy -0.7239 1.9939) (xy 0.7239 1.9939)
			)
			(stroke
				(width 0)
				(type default)
			)
			(fill no)
			(layer "B.CrtYd")
		)
		(fp_line
			(start -0.7239 -0.2159)
			(end 0.7239 -0.2159)
			(stroke
				(width 0.1)
				(type default)
			)
			(layer "B.Fab")
		)
		(fp_line
			(start -0.7239 1.9939)
			(end -0.7239 -0.2159)
			(stroke
				(width 0.1)
				(type default)
			)
			(layer "B.Fab")
		)
		(fp_line
			(start 0.7239 -0.2159)
			(end 0.7239 1.9939)
			(stroke
				(width 0.1)
				(type default)
			)
			(layer "B.Fab")
		)
		(fp_line
			(start 0.7239 1.9939)
			(end -0.7239 1.9939)
			(stroke
				(width 0.1)
				(type default)
			)
			(layer "B.Fab")
		)
		(pad "1" smd rect
			(at 0 0 180)
			(size 1.27 1.016)
			(layers "B.Cu" "B.Mask" "B.Paste")
			(net "PVDDQ_DEF")
		)
		(pad "2" smd rect
			(at 0 1.778 180)
			(size 1.27 1.016)
			(layers "B.Cu" "B.Mask" "B.Paste")
			(net "GND")
		)
		(zone
			(layer "B.Cu")
			(hatch none 0.5)
			(connect_pads
				(clearance 0)
			)
			(min_thickness 0.25)
			(keepout
				(tracks not_allowed)
				(vias allowed)
				(pads allowed)
				(copperpour not_allowed)
				(footprints allowed)
			)
			(placement
				(enabled no)
				(sheetname "")
			)
			(fill
				(thermal_gap 0.5)
				(thermal_bridge_width 0.5)
				(island_removal_mode 0)
			)
			(polygon
				(pts
					(xy 268.187424 -84.567014) (xy 266.917424 -84.567014) (xy 266.917424 -83.805014) (xy 268.187424 -83.805014)
				)
			)
		)
	)
	(footprint ""
		(layer "B.Cu")
		(at 481.203 -114.554 90)
		(property "Reference" "C1M21"
			(at 0 0 90)
			(layer "B.SilkS")
			(hide yes)
			(effects
				(font
					(size 1.27 1.27)
				)
				(justify mirror)
			)
		)
		(property "Value" ""
			(at 0 0 90)
			(layer "B.Fab")
			(effects
				(font
					(size 1.27 1.27)
				)
				(justify mirror)
			)
		)
		(duplicate_pad_numbers_are_jumpers no)
		(fp_rect
			(start 0.3048 -0.1016)
			(end -0.3048 0.9906)
			(stroke
				(width 0)
				(type default)
			)
			(fill no)
			(layer "B.CrtYd")
		)
		(fp_line
			(start 0.3048 -0.1016)
			(end 0.3048 0.9906)
			(stroke
				(width 0.1)
				(type default)
			)
			(layer "B.Fab")
		)
		(fp_line
			(start -0.3048 -0.1016)
			(end 0.3048 -0.1016)
			(stroke
				(width 0.1)
				(type default)
			)
			(layer "B.Fab")
		)
		(fp_line
			(start 0.3048 0.9906)
			(end -0.3048 0.9906)
			(stroke
				(width 0.1)
				(type default)
			)
			(layer "B.Fab")
		)
		(fp_line
			(start -0.3048 0.9906)
			(end -0.3048 -0.1016)
			(stroke
				(width 0.1)
				(type default)
			)
			(layer "B.Fab")
		)
		(pad "1" smd rect
			(at 0 0 270)
			(size 0.508 0.508)
			(layers "B.Cu" "B.Mask" "B.Paste")
			(net "P3V3")
		)
		(pad "2" smd rect
			(at 0 0.889 270)
			(size 0.508 0.508)
			(layers "B.Cu" "B.Mask" "B.Paste")
			(net "GND")
		)
		(zone
			(layer "B.Cu")
			(hatch none 0.5)
			(connect_pads
				(clearance 0)
			)
			(min_thickness 0.25)
			(keepout
				(tracks allowed)
				(vias not_allowed)
				(pads allowed)
				(copperpour not_allowed)
				(footprints allowed)
			)
			(placement
				(enabled no)
				(sheetname "")
			)
			(fill
				(thermal_gap 0.5)
				(thermal_bridge_width 0.5)
				(island_removal_mode 0)
			)
			(polygon
				(pts
					(xy 481.457 -114.808) (xy 481.457 -114.3) (xy 481.838 -114.3) (xy 481.838 -114.808)
				)
			)
		)
		(zone
			(layer "B.Cu")
			(hatch none 0.5)
			(connect_pads
				(clearance 0)
			)
			(min_thickness 0.25)
			(keepout
				(tracks not_allowed)
				(vias allowed)
				(pads allowed)
				(copperpour not_allowed)
				(footprints allowed)
			)
			(placement
				(enabled no)
				(sheetname "")
			)
			(fill
				(thermal_gap 0.5)
				(thermal_bridge_width 0.5)
				(island_removal_mode 0)
			)
			(polygon
				(pts
					(xy 481.457 -114.808) (xy 481.457 -114.3) (xy 481.838 -114.3) (xy 481.838 -114.808)
				)
			)
		)
	)
)
